# T6G (Grand Teton) — schematic parts with pin connectivity, parts 2612–2612 of 8303; source: Cadence DE-HDL packaged netlist (pstxprt.dat, pstxnet.dat, pstchip.dat)

J33  SCONN288_DDR506112002KQ  IO  pkg DDR288S_1-1VXC  page 103
  1  VIN_BULK0  POWER  = P12V_MEM_CPU1
  2  RFU0  TRI  = NC
  3  VIN_MGMT  POWER  = P3V3_AUX
  4  HSCL  IN  = I3C_SPD_DDRF_CPU1_SCL
  5  HSDA  BI  = I3C_SPD_DDRF_CPU1_SDA
  6  VSS0  POWER  = GND
  7  DQ0_A  BI  = M_F_CPU1_SA_DQ<0>
  8  VSS1  POWER  = GND
  9  DQ1_A  BI  = M_F_CPU1_SA_DQ<1>
  10  VSS2  POWER  = GND
  11  DQS0_A_T  BI  = M_F_CPU1_SA_DQS_DP<0>
  12  DQS0_A_C  BI  = M_F_CPU1_SA_DQS_DN<0>
  13  VSS3  POWER  = GND
  14  DQ4_A  BI  = M_F_CPU1_SA_DQ<4>
  15  VSS4  POWER  = GND
  16  DQ5_A  BI  = M_F_CPU1_SA_DQ<5>
  17  VSS5  POWER  = GND
  18  DQ8_A  BI  = M_F_CPU1_SA_DQ<8>
  19  VSS6  POWER  = GND
  20  DQ9_A  BI  = M_F_CPU1_SA_DQ<9>
  21  VSS7  POWER  = GND
  22  DQS1_A_T  BI  = M_F_CPU1_SA_DQS_DP<1>
  23  DQS1_A_C  BI  = M_F_CPU1_SA_DQS_DN<1>
  24  VSS8  POWER  = GND
  25  DQ12_A  BI  = M_F_CPU1_SA_DQ<12>
  26  VSS9  POWER  = GND
  27  DQ13_A  BI  = M_F_CPU1_SA_DQ<13>
  28  VSS10  POWER  = GND
  29  DQ16_A  BI  = M_F_CPU1_SA_DQ<16>
  30  VSS11  POWER  = GND
  31  DQ17_A  BI  = M_F_CPU1_SA_DQ<17>
  32  VSS12  POWER  = GND
  33  DQS2_A_T  BI  = M_F_CPU1_SA_DQS_DP<2>
  34  DQS2_A_C  BI  = M_F_CPU1_SA_DQS_DN<2>
  35  VSS13  POWER  = GND
  36  DQ20_A  BI  = M_F_CPU1_SA_DQ<20>
  37  VSS14  POWER  = GND
  38  DQ21_A  BI  = M_F_CPU1_SA_DQ<21>
  39  VSS15  POWER  = GND
  40  DQ24_A  BI  = M_F_CPU1_SA_DQ<24>
  41  VSS16  POWER  = GND
  42  DQ25_A  BI  = M_F_CPU1_SA_DQ<25>
  43  VSS17  POWER  = GND
  44  DQS3_A_T  BI  = M_F_CPU1_SA_DQS_DP<3>
  45  DQS3_A_C  BI  = M_F_CPU1_SA_DQS_DN<3>
  46  VSS18  POWER  = GND
  47  DQ28_A  BI  = M_F_CPU1_SA_DQ<28>
  48  VSS19  POWER  = GND
  49  DQ29_A  BI  = M_F_CPU1_SA_DQ<29>
  50  VSS20  POWER  = GND
  51  CB0_A  BI  = M_F_CPU1_SA_CB<0>
  52  VSS21  POWER  = GND
  53  CB1_A  BI  = M_F_CPU1_SA_CB<1>
  54  VSS22  POWER  = GND
  55  DQS4_A_T  BI  = M_F_CPU1_SA_DQS_DP<4>
  56  DQS4_A_C  BI  = M_F_CPU1_SA_DQS_DN<4>
  57  VSS23  POWER  = GND
  58  CB4_A  BI  = M_F_CPU1_SA_CB<4>
  59  VSS24  POWER  = GND
  60  CB5_A  BI  = M_F_CPU1_SA_CB<5>
  61  VSS25  POWER  = GND
  62  ALERT_N  OUT  = M_F_CPU1_ALERT_N
  63  VSS26  POWER  = GND
  64  CS0_A_N  IN  = M_F_CPU1_SA_CS_N<0>
  65  VSS27  POWER  = GND
  66  CA0_A  IN  = M_F_CPU1_SA_CA<0>
  67  VSS28  POWER  = GND
  68  CA2_A  IN  = M_F_CPU1_SA_CA<2>
  69  VSS29  POWER  = GND
  70  CA4_A  IN  = M_F_CPU1_SA_CA<4>
  71  VSS30  POWER  = GND
  72  CA6_A  IN  = M_F_CPU1_SA_CA<6>
  73  VSS31  POWER  = GND
  74  PAR_A  IN  = M_F_CPU1_SA_PAR
  75  VSS32  POWER  = GND
  76  CA0_B  IN  = M_F_CPU1_SB_CA<0>
  77  VSS33  POWER  = GND
  78  CA2_B  IN  = M_F_CPU1_SB_CA<2>
  79  VSS34  POWER  = GND
  80  CA4_B  IN  = M_F_CPU1_SB_CA<4>
  81  VSS35  POWER  = GND
  82  CA6_B  IN  = M_F_CPU1_SB_CA<6>
  83  VSS36  POWER  = GND
  84  CS0_B_N  IN  = M_F_CPU1_SB_CS_N<0>
  85  VSS37  POWER  = GND
  86  \lbd||rsp_a_n\  OUT  = M_F_CPU1_SA_RSP<0>
  87  \lbs||rsp_b_n\  OUT  = M_F_CPU1_SB_RSP<0>
  88  VSS38  POWER  = GND
  89  CB4_B  BI  = M_F_CPU1_SB_CB<4>
  90  VSS39  POWER  = GND
  91  CB5_B  BI  = M_F_CPU1_SB_CB<5>
  92  VSS40  POWER  = GND
  93  \dqs9_b_t||tdqs9_b_t||dbi4_b_n\  BI  = M_F_CPU1_SB_DQS_DP<9>
  94  \dqs9_b_c||tdqs9_b_c\  BI  = M_F_CPU1_SB_DQS_DN<9>
  95  VSS41  POWER  = GND
  96  CB0_B  BI  = M_F_CPU1_SB_CB<0>
  97  VSS42  POWER  = GND
  98  CB1_B  BI  = M_F_CPU1_SB_CB<1>
  99  VSS43  POWER  = GND
  100  DQ0_B  BI  = M_F_CPU1_SB_DQ<0>
  101  VSS44  POWER  = GND
  102  DQ1_B  BI  = M_F_CPU1_SB_DQ<1>
  103  VSS45  POWER  = GND
  104  DQS0_B_T  BI  = M_F_CPU1_SB_DQS_DP<0>
  105  DQS0_B_C  BI  = M_F_CPU1_SB_DQS_DN<0>
  106  VSS46  POWER  = GND
  107  DQ4_B  BI  = M_F_CPU1_SB_DQ<4>
  108  VSS47  POWER  = GND
  109  DQ5_B  BI  = M_F_CPU1_SB_DQ<5>
  110  VSS48  POWER  = GND
  111  DQ8_B  BI  = M_F_CPU1_SB_DQ<8>
  112  VSS49  POWER  = GND
  113  DQ9_B  BI  = M_F_CPU1_SB_DQ<9>
  114  VSS50  POWER  = GND
  115  DQS1_B_T  BI  = M_F_CPU1_SB_DQS_DP<1>
  116  DQS1_B_C  BI  = M_F_CPU1_SB_DQS_DN<1>
  117  VSS51  POWER  = GND
  118  DQ12_B  BI  = M_F_CPU1_SB_DQ<12>
  119  VSS52  POWER  = GND
  120  DQ13_B  BI  = M_F_CPU1_SB_DQ<13>
  121  VSS53  POWER  = GND
  122  DQ16_B  BI  = M_F_CPU1_SB_DQ<16>
  123  VSS54  POWER  = GND
  124  DQ17_B  BI  = M_F_CPU1_SB_DQ<17>
  125  VSS55  POWER  = GND
  126  DQS2_B_T  BI  = M_F_CPU1_SB_DQS_DP<2>
  127  DQS2_B_C  BI  = M_F_CPU1_SB_DQS_DN<2>
  128  VSS56  POWER  = GND
  129  DQ20_B  BI  = M_F_CPU1_SB_DQ<20>
  130  VSS57  POWER  = GND
  131  DQ21_B  BI  = M_F_CPU1_SB_DQ<21>
  132  VSS58  POWER  = GND
  133  DQ24_B  BI  = M_F_CPU1_SB_DQ<24>
  134  VSS59  POWER  = GND
  135  DQ25_B  BI  = M_F_CPU1_SB_DQ<25>
  136  VSS60  POWER  = GND
  137  DQS3_B_T  BI  = M_F_CPU1_SB_DQS_DP<3>
  138  DQS3_B_C  BI  = M_F_CPU1_SB_DQS_DN<3>
  139  VSS61  POWER  = GND
  140  DQ28_B  BI  = M_F_CPU1_SB_DQ<28>
  141  VSS62  POWER  = GND
  142  DQ29_B  BI  = M_F_CPU1_SB_DQ<29>
  143  VSS63  POWER  = GND
  144  RFU1  TRI  = NC
  145  VIN_BULK1  POWER  = P12V_MEM_CPU1
  146  VIN_BULK2  POWER  = P12V_MEM_CPU1
  147  \pwr_good||fail_n\  BI  = PWRGD_CHF_CPU1_DIMM
  148  HAS  IN  = PD_CHF_CPU1_DIMM_SAA
  149  RFU2  TRI  = NC
  150  RFU3  TRI  = NC
  151  VSS64  POWER  = GND
  152  DQ2_A  BI  = M_F_CPU1_SA_DQ<2>
  153  VSS65  POWER  = GND
  154  DQ3_A  BI  = M_F_CPU1_SA_DQ<3>
  155  VSS66  POWER  = GND
  156  \dqs5_a_c||tdqs5_a_c||dqs5_a_t||tdqs5_a_t\  BI  = M_F_CPU1_SA_DQS_DN<5>
  157  \dqs5_a_t||tdqs5_a_t\  BI  = M_F_CPU1_SA_DQS_DP<5>
  158  VSS67  POWER  = GND
  159  DQ6_A  BI  = M_F_CPU1_SA_DQ<6>
  160  VSS68  POWER  = GND
  161  DQ7_A  BI  = M_F_CPU1_SA_DQ<7>
  162  VSS69  POWER  = GND
  163  DQ10_A  BI  = M_F_CPU1_SA_DQ<10>
  164  VSS70  POWER  = GND
  165  DQ11_A  BI  = M_F_CPU1_SA_DQ<11>
  166  VSS71  POWER  = GND
  167  \dqs6_a_c||tdqs6_a_c||dqs6_a_t||tdqs6_a_t\  BI  = M_F_CPU1_SA_DQS_DN<6>
  168  \dqs6_a_t||tdqs6_a_t\  BI  = M_F_CPU1_SA_DQS_DP<6>
  169  VSS72  POWER  = GND
  170  DQ14_A  BI  = M_F_CPU1_SA_DQ<14>
  171  VSS73  POWER  = GND
  172  DQ15_A  BI  = M_F_CPU1_SA_DQ<15>
  173  VSS74  POWER  = GND
  174  DQ18_A  BI  = M_F_CPU1_SA_DQ<18>
  175  VSS75  POWER  = GND
  176  DQ19_A  BI  = M_F_CPU1_SA_DQ<19>
  177  VSS76  POWER  = GND
  178  \dqs7_a_c||tdqs7_a_c\  BI  = M_F_CPU1_SA_DQS_DN<7>
  179  \dqs7_a_t||tdqs7_a_t\  BI  = M_F_CPU1_SA_DQS_DP<7>
  180  VSS77  POWER  = GND
  181  DQ22_A  BI  = M_F_CPU1_SA_DQ<22>
  182  VSS78  POWER  = GND
  183  DQ23_A  BI  = M_F_CPU1_SA_DQ<23>
  184  VSS79  POWER  = GND
  185  DQ26_A  BI  = M_F_CPU1_SA_DQ<26>
  186  VSS80  POWER  = GND
  187  DQ27_A  BI  = M_F_CPU1_SA_DQ<27>
  188  VSS81  POWER  = GND
  189  \dqs8_a_c||tdqs8_a_c\  BI  = M_F_CPU1_SA_DQS_DN<8>
  190  \dqs8_a_t||tdqs8_a_t\  BI  = M_F_CPU1_SA_DQS_DP<8>
  191  VSS82  POWER  = GND
  192  DQ30_A  BI  = M_F_CPU1_SA_DQ<30>
  193  VSS83  POWER  = GND
  194  DQ31_A  BI  = M_F_CPU1_SA_DQ<31>
  195  VSS84  POWER  = GND
  196  CB2_A  BI  = M_F_CPU1_SA_CB<2>
  197  VSS85  POWER  = GND
  198  CB3_A  BI  = M_F_CPU1_SA_CB<3>
  199  VSS86  POWER  = GND
  200  \dqs9_a_c||tdqs9_a_c\  BI  = M_F_CPU1_SA_DQS_DN<9>
  201  \dqs9_a_t||tdqs9_a_t\  BI  = M_F_CPU1_SA_DQS_DP<9>
  202  VSS87  POWER  = GND
  203  CB6_A  BI  = M_F_CPU1_SA_CB<6>
  204  VSS88  POWER  = GND
  205  CB7_A  BI  = M_F_CPU1_SA_CB<7>
  206  VSS89  POWER  = GND
  207  RESET_N  IN  = M_F_CPU1_RESET_N
  208  VSS90  POWER  = GND
  209  CS1_A_N  IN  = M_F_CPU1_SA_CS_N<1>
  210  VSS91  POWER  = GND
  211  CA1_A  IN  = M_F_CPU1_SA_CA<1>
  212  VSS92  POWER  = GND
  213  CA3_A  IN  = M_F_CPU1_SA_CA<3>
  214  VSS93  POWER  = GND
  215  CA5_A  IN  = M_F_CPU1_SA_CA<5>
  216  VSS94  POWER  = GND
  217  CK_T  IN  = M_F_CPU1_CLK_DP<0>
  218  CK_C  IN  = M_F_CPU1_CLK_DN<0>
  219  VSS95  POWER  = GND
  220  RFU4  TRI  = NC
  221  CA1_B  IN  = M_F_CPU1_SB_CA<1>
  222  VSS96  POWER  = GND
  223  CA3_B  IN  = M_F_CPU1_SB_CA<3>
  224  VSS97  POWER  = GND
  225  CA5_B  IN  = M_F_CPU1_SB_CA<5>
  226  VSS98  POWER  = GND
  227  PAR_B  IN  = M_F_CPU1_SB_PAR
  228  VSS99  POWER  = GND
  229  CS1_B_N  IN  = M_F_CPU1_SB_CS_N<1>
  230  VSS100  POWER  = GND
  231  RFU5  TRI  = NC
  232  RFU6  TRI  = NC
  233  VSS101  POWER  = GND
  234  CB6_B  BI  = M_F_CPU1_SB_CB<6>
  235  VSS102  POWER  = GND
  236  CB7_B  BI  = M_F_CPU1_SB_CB<7>
  237  VSS103  POWER  = GND
  238  DQS4_B_C  BI  = M_F_CPU1_SB_DQS_DN<4>
  239  DQS4_B_T  BI  = M_F_CPU1_SB_DQS_DP<4>
  240  VSS104  POWER  = GND
  241  CB2_B  BI  = M_F_CPU1_SB_CB<2>
  242  VSS105  POWER  = GND
  243  CB3_B  BI  = M_F_CPU1_SB_CB<3>
  244  VSS106  POWER  = GND
  245  DQ2_B  BI  = M_F_CPU1_SB_DQ<2>
  246  VSS107  POWER  = GND
  247  DQ3_B  BI  = M_F_CPU1_SB_DQ<3>
  248  VSS108  POWER  = GND
  249  \dqs5_b_c||tdqs5_b_c\  BI  = M_F_CPU1_SB_DQS_DN<5>
  250  \dqs5_b_t||tdqs5_b_t\  BI  = M_F_CPU1_SB_DQS_DP<5>
  251  VSS109  POWER  = GND
  252  DQ6_B  BI  = M_F_CPU1_SB_DQ<6>
  253  VSS110  POWER  = GND
  254  DQ7_B  BI  = M_F_CPU1_SB_DQ<7>
  255  VSS111  POWER  = GND
  256  DQ10_B  BI  = M_F_CPU1_SB_DQ<10>
  257  VSS112  POWER  = GND
  258  DQ11_B  BI  = M_F_CPU1_SB_DQ<11>
  259  VSS113  POWER  = GND
  260  \dqs6_b_c||tdqs6_b_c\  BI  = M_F_CPU1_SB_DQS_DN<6>
  261  \dqs6_b_t||tdqs6_b_t\  BI  = M_F_CPU1_SB_DQS_DP<6>
  262  VSS114  POWER  = GND
  263  DQ14_B  BI  = M_F_CPU1_SB_DQ<14>
  264  VSS115  POWER  = GND
  265  DQ15_B  BI  = M_F_CPU1_SB_DQ<15>
  266  VSS116  POWER  = GND
  267  DQ18_B  BI  = M_F_CPU1_SB_DQ<18>
  268  VSS117  POWER  = GND
  269  DQ19_B  BI  = M_F_CPU1_SB_DQ<19>
  270  VSS118  POWER  = GND
  271  \dqs7_b_c||tdqs7_b_c\  BI  = M_F_CPU1_SB_DQS_DN<7>
  272  \dqs7_b_t||tdqs7_b_t\  BI  = M_F_CPU1_SB_DQS_DP<7>
  273  VSS119  POWER  = GND
  274  DQ22_B  BI  = M_F_CPU1_SB_DQ<22>
  275  VSS120  POWER  = GND
  276  DQ23_B  BI  = M_F_CPU1_SB_DQ<23>
  277  VSS121  POWER  = GND
  278  DQ26_B  BI  = M_F_CPU1_SB_DQ<26>
  279  VSS122  POWER  = GND
  280  DQ27_B  BI  = M_F_CPU1_SB_DQ<27>
  281  VSS123  POWER  = GND
  282  \dqs8_b_c||tdqs8_b_c\  BI  = M_F_CPU1_SB_DQS_DN<8>
  283  \dqs8_b_t||tdqs8_b_t\  BI  = M_F_CPU1_SB_DQS_DP<8>
  284  VSS124  POWER  = GND
  285  DQ30_B  BI  = M_F_CPU1_SB_DQ<30>
  286  VSS125  POWER  = GND
  287  DQ31_B  BI  = M_F_CPU1_SB_DQ<31>
  288  VSS126  POWER  = GND
  G1  G1  POWER  = GND
  G2  G2  POWER  = GND
  G3  G3  POWER  = GND
